FILE_TYPE = MULTI_PHYS_TABLE;

PART 'PT5161LRS'

{========================================================================================}
:VALUE       | PART_TYPE | MATERIAL | PART_NUMBER    = STANDARD | LIFECYCLE          | PART_NUMBER   | JEDEC_TYPE        | DESCRIPTION                 | MANUFTR | MANUF_PN    | RD_CMPLS_LVL | CMPLS_LVL | FROM_PJ   | CLASS | DIP_SMD | DATA                | EE_CHECK_LIST | FP_ECN          | PSL | CREATOR | STATUS | MSD | ESD_CDM | ESD_HBM | ESD_MM | PIN_LENGTH_SHORT_PIN | PIN_LENGTH_LONG_PIN | CREATEDAY  ;
{========================================================================================}
 'PT5161LRS' | 'SMLF'    | 'IC'     | 'AJ051610U03'(!) = 'End of Design'  | 'Comp-Approve'   | 'AJ051610U03' |'BGA354_8-9X22-8'| 'IC(354P)PT5161LRS(FC-CSP)' | 'AEB'   | 'PT5161LRS' | 'EP(V1)'     | ''        | 'S7P-JIM' | 'IC'  | ''      | 'AEB_PT5161LRS.pdf' | ''            | 'PT5161LRS.msg' | ''  | ''      | ''     | ''  | ''      | ''      | ''     | '0 MILS'             | '0 MILS'            | '20220512'
 'PT5161LRS' | 'SMLF'    | 'EMPTY'  | 'AJ051610U03'(!) = 'End of Design'  | 'Comp-Approve'   | 'AJ051610U03' |'BGA354_8-9X22-8'| 'IC(354P)PT5161LRS(FC-CSP)' | 'AEB'   | 'PT5161LRS' | 'EP(V1)'     | ''        | 'S7P-JIM' | 'IC'  | ''      | 'AEB_PT5161LRS.pdf' | ''            | 'PT5161LRS.msg' | ''  | ''      | ''     | ''  | ''      | ''      | ''     | '0 MILS'             | '0 MILS'            | '20220512'

END_PART

END.

